# T6G (Grand Teton) — schematic netlist excerpt (pin names and nets, part order shuffled) for the footprints in the layout excerpt that follows; sources: Cadence DE-HDL packaged netlist, KiCad conversion of 04192023_DAF0TMB3IC0_F0TG_MB_C_brd_V02_OCP.brd

C7039  Q_CAP  47UF 4V 20% X6S  pkg C0805  page 345 : A = P0V9_CPU1_RT_2D ; B = GND
PC376_2  Q_CAP  0.1UF 25V 10% X7R  pkg 0402  page 218 : A = SW_P12V_AUX_PVDDCR_CPU1_P1_FLT ; B = GND
C15  Q_CAP  0.1UF 25V 10% X7R  pkg 0402  page 125 : A = PRSNT_CABLE_GPU_A1_ISO_N ; B = GND

(kicad_pcb
	(version 20260206)
	(generator "pcbnew")
	(generator_version "10.0")
	(general
		(thickness 1.6)
		(legacy_teardrops no)
	)
	(paper "A4")
	(title_block
		(title "04192023_DAF0TMB3IC0_F0TG_MB_C_brd_V02_OCP.brd")
		(comment 1 "Grand Teton / footprints 1692-1694 of 8354")
	)
	(layers
		(0 "F.Cu" signal "TOP")
		(4 "In1.Cu" signal "GND")
		(6 "In2.Cu" signal "IN1")
		(8 "In3.Cu" signal "GND1")
		(10 "In4.Cu" signal "IN2")
		(12 "In5.Cu" signal "GND2")
		(14 "In6.Cu" signal "IN3")
		(16 "In7.Cu" signal "GND3")
		(18 "In8.Cu" signal "VCC")
		(20 "In9.Cu" signal "VCC1")
		(22 "In10.Cu" signal "GND4")
		(24 "In11.Cu" signal "IN4")
		(26 "In12.Cu" signal "GND5")
		(28 "In13.Cu" signal "IN5")
		(30 "In14.Cu" signal "GND6")
		(32 "In15.Cu" signal "IN6")
		(34 "In16.Cu" signal "GND7")
		(2 "B.Cu" signal "BOTTOM")
		(9 "F.Adhes" user "F.Adhesive")
		(11 "B.Adhes" user "B.Adhesive")
		(13 "F.Paste" user "Package Geometry/Pastemask Top")
		(15 "B.Paste" user "Package Geometry/Pastemask Bottom")
		(5 "F.SilkS" user "Ref Des/Silkscreen Top")
		(7 "B.SilkS" user "Ref Des/Silkscreen Bottom")
		(1 "F.Mask" user "Board Geometry/Soldermask Top")
		(3 "B.Mask" user "Board Geometry/Soldermask Bottom")
		(17 "Dwgs.User" user "User.Drawings")
		(19 "Cmts.User" user "User.Comments")
		(21 "Eco1.User" user "User.Eco1")
		(23 "Eco2.User" user "User.Eco2")
		(25 "Edge.Cuts" user "Board Geometry/Outline")
		(27 "Margin" user)
		(31 "F.CrtYd" user "Package Geometry/Place Bound Top")
		(29 "B.CrtYd" user "Package Geometry/Place Bound Bottom")
		(35 "F.Fab" user "Ref Des/Assembly Top")
		(33 "B.Fab" user "Ref Des/Assembly Bottom")
	)
	(footprint ""
		(layer "F.Cu")
		(at 357.284782 -412.030418)
		(property "Reference" "C15"
			(at 0 0 0)
			(layer "F.SilkS")
			(hide yes)
			(effects
				(font
					(size 1.27 1.27)
				)
			)
		)
		(property "Value" ""
			(at 0 0 0)
			(layer "F.Fab")
			(effects
				(font
					(size 1.27 1.27)
				)
			)
		)
		(duplicate_pad_numbers_are_jumpers no)
		(fp_line
			(start -0.7874 -0.4064)
			(end 0.7874 -0.4064)
			(stroke
				(width 0.1524)
				(type default)
			)
			(layer "F.SilkS")
		)
		(fp_line
			(start -0.7874 0.4064)
			(end -0.7874 -0.4064)
			(stroke
				(width 0.1524)
				(type default)
			)
			(layer "F.SilkS")
		)
		(fp_line
			(start 0.7874 -0.4064)
			(end 0.7874 0.4064)
			(stroke
				(width 0.1524)
				(type default)
			)
			(layer "F.SilkS")
		)
		(fp_line
			(start 0.7874 0.4064)
			(end -0.7874 0.4064)
			(stroke
				(width 0.1524)
				(type default)
			)
			(layer "F.SilkS")
		)
		(fp_line
			(start -0.67945 -0.305054)
			(end -0.12065 -0.305054)
			(stroke
				(width 0.1)
				(type default)
			)
			(layer "F.Fab")
		)
		(fp_line
			(start -0.67945 0.3048)
			(end -0.67945 -0.305054)
			(stroke
				(width 0.1)
				(type default)
			)
			(layer "F.Fab")
		)
		(fp_line
			(start -0.12065 -0.305054)
			(end -0.12065 -0.2794)
			(stroke
				(width 0.1)
				(type default)
			)
			(layer "F.Fab")
		)
		(fp_line
			(start -0.12065 -0.2794)
			(end 0.12065 -0.2794)
			(stroke
				(width 0.1)
				(type default)
			)
			(layer "F.Fab")
		)
		(fp_line
			(start -0.12065 0.2794)
			(end -0.12065 0.3048)
			(stroke
				(width 0.1)
				(type default)
			)
			(layer "F.Fab")
		)
		(fp_line
			(start -0.12065 0.3048)
			(end -0.67945 0.3048)
			(stroke
				(width 0.1)
				(type default)
			)
			(layer "F.Fab")
		)
		(fp_line
			(start 0.120396 0.2794)
			(end -0.12065 0.2794)
			(stroke
				(width 0.1)
				(type default)
			)
			(layer "F.Fab")
		)
		(fp_line
			(start 0.120396 0.3048)
			(end 0.120396 0.2794)
			(stroke
				(width 0.1)
				(type default)
			)
			(layer "F.Fab")
		)
		(fp_line
			(start 0.12065 -0.3048)
			(end 0.67945 -0.3048)
			(stroke
				(width 0.1)
				(type default)
			)
			(layer "F.Fab")
		)
		(fp_line
			(start 0.12065 -0.2794)
			(end 0.12065 -0.3048)
			(stroke
				(width 0.1)
				(type default)
			)
			(layer "F.Fab")
		)
		(fp_line
			(start 0.67945 -0.3048)
			(end 0.67945 0.3048)
			(stroke
				(width 0.1)
				(type default)
			)
			(layer "F.Fab")
		)
		(fp_line
			(start 0.67945 0.3048)
			(end 0.120396 0.3048)
			(stroke
				(width 0.1)
				(type default)
			)
			(layer "F.Fab")
		)
		(pad "1" smd circle
			(at -0.40005 0)
			(size 0 0)
			(layers "F.Cu" "F.Mask" "F.Paste")
			(net "PRSNT_CABLE_GPU_A1_ISO_N")
		)
		(pad "2" smd circle
			(at 0.40005 0)
			(size 0 0)
			(layers "F.Cu" "F.Mask" "F.Paste")
			(net "GND")
		)
	)
	(footprint ""
		(layer "F.Cu")
		(at 74.628502 -339.377274)
		(property "Reference" "PC376_2"
			(at 0 0 0)
			(layer "F.SilkS")
			(hide yes)
			(effects
				(font
					(size 1.27 1.27)
				)
			)
		)
		(property "Value" ""
			(at 0 0 0)
			(layer "F.Fab")
			(effects
				(font
					(size 1.27 1.27)
				)
			)
		)
		(duplicate_pad_numbers_are_jumpers no)
		(fp_line
			(start -0.7874 -0.4064)
			(end 0.7874 -0.4064)
			(stroke
				(width 0.1524)
				(type default)
			)
			(layer "F.SilkS")
		)
		(fp_line
			(start -0.7874 0.4064)
			(end -0.7874 -0.4064)
			(stroke
				(width 0.1524)
				(type default)
			)
			(layer "F.SilkS")
		)
		(fp_line
			(start 0.7874 -0.4064)
			(end 0.7874 0.4064)
			(stroke
				(width 0.1524)
				(type default)
			)
			(layer "F.SilkS")
		)
		(fp_line
			(start 0.7874 0.4064)
			(end -0.7874 0.4064)
			(stroke
				(width 0.1524)
				(type default)
			)
			(layer "F.SilkS")
		)
		(fp_line
			(start -0.67945 -0.305054)
			(end -0.12065 -0.305054)
			(stroke
				(width 0.1)
				(type default)
			)
			(layer "F.Fab")
		)
		(fp_line
			(start -0.67945 0.3048)
			(end -0.67945 -0.305054)
			(stroke
				(width 0.1)
				(type default)
			)
			(layer "F.Fab")
		)
		(fp_line
			(start -0.12065 -0.305054)
			(end -0.12065 -0.2794)
			(stroke
				(width 0.1)
				(type default)
			)
			(layer "F.Fab")
		)
		(fp_line
			(start -0.12065 -0.2794)
			(end 0.12065 -0.2794)
			(stroke
				(width 0.1)
				(type default)
			)
			(layer "F.Fab")
		)
		(fp_line
			(start -0.12065 0.2794)
			(end -0.12065 0.3048)
			(stroke
				(width 0.1)
				(type default)
			)
			(layer "F.Fab")
		)
		(fp_line
			(start -0.12065 0.3048)
			(end -0.67945 0.3048)
			(stroke
				(width 0.1)
				(type default)
			)
			(layer "F.Fab")
		)
		(fp_line
			(start 0.120396 0.2794)
			(end -0.12065 0.2794)
			(stroke
				(width 0.1)
				(type default)
			)
			(layer "F.Fab")
		)
		(fp_line
			(start 0.120396 0.3048)
			(end 0.120396 0.2794)
			(stroke
				(width 0.1)
				(type default)
			)
			(layer "F.Fab")
		)
		(fp_line
			(start 0.12065 -0.3048)
			(end 0.67945 -0.3048)
			(stroke
				(width 0.1)
				(type default)
			)
			(layer "F.Fab")
		)
		(fp_line
			(start 0.12065 -0.2794)
			(end 0.12065 -0.3048)
			(stroke
				(width 0.1)
				(type default)
			)
			(layer "F.Fab")
		)
		(fp_line
			(start 0.67945 -0.3048)
			(end 0.67945 0.3048)
			(stroke
				(width 0.1)
				(type default)
			)
			(layer "F.Fab")
		)
		(fp_line
			(start 0.67945 0.3048)
			(end 0.120396 0.3048)
			(stroke
				(width 0.1)
				(type default)
			)
			(layer "F.Fab")
		)
		(pad "1" smd circle
			(at -0.40005 0)
			(size 0 0)
			(layers "F.Cu" "F.Mask" "F.Paste")
			(net "SW_P12V_AUX_PVDDCR_CPU1_P1_FLT")
		)
		(pad "2" smd circle
			(at 0.40005 0)
			(size 0 0)
			(layers "F.Cu" "F.Mask" "F.Paste")
			(net "GND")
		)
	)
	(footprint ""
		(layer "F.Cu")
		(at 76.184252 -401.925536 90)
		(property "Reference" "C7039"
			(at 0 0 90)
			(layer "F.SilkS")
			(hide yes)
			(effects
				(font
					(size 1.27 1.27)
				)
			)
		)
		(property "Value" ""
			(at 0 0 90)
			(layer "F.Fab")
			(effects
				(font
					(size 1.27 1.27)
				)
			)
		)
		(duplicate_pad_numbers_are_jumpers no)
		(fp_line
			(start 1.524 -0.762)
			(end 1.524 0.762)
			(stroke
				(width 0.1524)
				(type default)
			)
			(layer "F.SilkS")
		)
		(fp_line
			(start -1.524 -0.762)
			(end 1.524 -0.762)
			(stroke
				(width 0.1524)
				(type default)
			)
			(layer "F.SilkS")
		)
		(fp_line
			(start 1.524 0.762)
			(end -1.524 0.762)
			(stroke
				(width 0.1524)
				(type default)
			)
			(layer "F.SilkS")
		)
		(fp_line
			(start -1.524 0.762)
			(end -1.524 -0.762)
			(stroke
				(width 0.1524)
				(type default)
			)
			(layer "F.SilkS")
		)
		(fp_line
			(start 1.1049 -0.724916)
			(end -1.1049 -0.724916)
			(stroke
				(width 0.1)
				(type default)
			)
			(layer "F.Fab")
		)
		(fp_line
			(start -1.1049 -0.724916)
			(end -1.1049 0.724916)
			(stroke
				(width 0.1)
				(type default)
			)
			(layer "F.Fab")
		)
		(fp_line
			(start 1.1049 0.724916)
			(end 1.1049 -0.724916)
			(stroke
				(width 0.1)
				(type default)
			)
			(layer "F.Fab")
		)
		(fp_line
			(start -1.1049 0.724916)
			(end 1.1049 0.724916)
			(stroke
				(width 0.1)
				(type default)
			)
			(layer "F.Fab")
		)
		(pad "1" smd rect
			(at -0.889 0 270)
			(size 1.016 1.27)
			(layers "F.Cu" "F.Mask" "F.Paste")
			(net "P0V9_CPU1_RT_2D")
		)
		(pad "2" smd rect
			(at 0.889 0 270)
			(size 1.016 1.27)
			(layers "F.Cu" "F.Mask" "F.Paste")
			(net "GND")
		)
	)
)
